(kicad_pcb
	(version 20260206)
	(generator "pcbnew")
	(generator_version "10.0")
	(general
		(thickness 1.6)
		(legacy_teardrops no)
	)
	(paper "A4")
	(title_block
		(title "01162023_DA0F0TEBIF0_F0T_Expander_BD_F_brd_V02_OCP.brd")
		(comment 1 "Grand Teton / footprint 2274 of 9728 (J22), pads 1-109 of 179")
	)
	(layers
		(0 "F.Cu" signal "TOP")
		(4 "In1.Cu" signal "GND")
		(6 "In2.Cu" signal "VCC")
		(8 "In3.Cu" signal "VCC1")
		(10 "In4.Cu" signal "GND1")
		(12 "In5.Cu" signal "IN1")
		(14 "In6.Cu" signal "GND2")
		(16 "In7.Cu" signal "IN2")
		(18 "In8.Cu" signal "GND3")
		(20 "In9.Cu" signal "IN3")
		(22 "In10.Cu" signal "GND4")
		(24 "In11.Cu" signal "IN4")
		(26 "In12.Cu" signal "GND5")
		(28 "In13.Cu" signal "IN5")
		(30 "In14.Cu" signal "GND6")
		(32 "In15.Cu" signal "IN6")
		(34 "In16.Cu" signal "GND7")
		(2 "B.Cu" signal "BOTTOM")
		(9 "F.Adhes" user "F.Adhesive")
		(11 "B.Adhes" user "B.Adhesive")
		(13 "F.Paste" user "Package Geometry/Pastemask Top")
		(15 "B.Paste" user "Package Geometry/Pastemask Bottom")
		(5 "F.SilkS" user "Ref Des/Silkscreen Top")
		(7 "B.SilkS" user "Ref Des/Silkscreen Bottom")
		(1 "F.Mask" user "Board Geometry/Soldermask Top")
		(3 "B.Mask" user "Board Geometry/Soldermask Bottom")
		(17 "Dwgs.User" user "User.Drawings")
		(19 "Cmts.User" user "User.Comments")
		(21 "Eco1.User" user "User.Eco1")
		(23 "Eco2.User" user "User.Eco2")
		(25 "Edge.Cuts" user "Board Geometry/Outline")
		(27 "Margin" user)
		(31 "F.CrtYd" user "Package Geometry/Place Bound Top")
		(29 "B.CrtYd" user "Package Geometry/Place Bound Bottom")
		(35 "F.Fab" user "Ref Des/Assembly Top")
		(33 "B.Fab" user "Ref Des/Assembly Bottom")
	)
	(footprint ""
		(layer "F.Cu")
		(at 163.41979 -127.700024)
		(property "Reference" "J22"
			(at -5.48132 34.685224 90)
			(unlocked yes)
			(layer "F.SilkS")
			(effects
				(font
					(size 0.7874 0.5842)
					(thickness 0.1524)
				)
				(justify left)
			)
		)
		(property "Value" ""
			(at 0 0 0)
			(layer "F.Fab")
			(effects
				(font
					(size 1.27 1.27)
				)
			)
		)
		(duplicate_pad_numbers_are_jumpers no)
		(pad "" np_thru_hole circle
			(at -0.727456 -32.485076)
			(size 1.1176 1.1176)
			(drill 1.1176)
			(layers "*.Cu" "*.Mask")
			(clearance 0.381)
			(thermal_gap 0.381)
		)
		(pad "" np_thru_hole circle
			(at 1.022604 32.485076)
			(size 1.1176 1.1176)
			(drill 1.1176)
			(layers "*.Cu" "*.Mask")
			(clearance 0.381)
			(thermal_gap 0.381)
		)
		(pad "A1" smd rect
			(at 3.322574 -18.465038 270)
			(size 0.3556 1.2192)
			(layers "F.Cu" "F.Mask" "F.Paste")
			(net "GND")
		)
		(pad "A2" smd rect
			(at 3.322574 -17.86509 270)
			(size 0.3556 1.2192)
			(layers "F.Cu" "F.Mask" "F.Paste")
			(net "GND")
		)
		(pad "A3" smd rect
			(at 3.322574 -17.264888 270)
			(size 0.3556 1.2192)
			(layers "F.Cu" "F.Mask" "F.Paste")
			(net "GND")
		)
		(pad "A4" smd rect
			(at 3.322574 -16.66494 270)
			(size 0.3556 1.2192)
			(layers "F.Cu" "F.Mask" "F.Paste")
			(net "GND")
		)
		(pad "A5" smd rect
			(at 3.322574 -16.064992 270)
			(size 0.3556 1.2192)
			(layers "F.Cu" "F.Mask" "F.Paste")
			(net "GND")
		)
		(pad "A6" smd rect
			(at 3.322574 -15.465044 270)
			(size 0.3556 1.2192)
			(layers "F.Cu" "F.Mask" "F.Paste")
			(net "GND")
		)
		(pad "A7" smd rect
			(at 3.322574 -14.865096 270)
			(size 0.3556 1.2192)
			(layers "F.Cu" "F.Mask" "F.Paste")
			(net "SMB_NIC2_R_SCL")
		)
		(pad "A8" smd rect
			(at 3.322574 -14.264894 270)
			(size 0.3556 1.2192)
			(layers "F.Cu" "F.Mask" "F.Paste")
			(net "SMB_NIC2_R_SDA")
		)
		(pad "A9" smd rect
			(at 3.322574 -13.664946 270)
			(size 0.3556 1.2192)
			(layers "F.Cu" "F.Mask" "F.Paste")
			(net "RST_SMB_NIC2_MUX_ISO_R_N")
		)
		(pad "A10" smd rect
			(at 3.322574 -13.064998 270)
			(size 0.3556 1.2192)
			(layers "F.Cu" "F.Mask" "F.Paste")
			(net "GND")
		)
		(pad "A11" smd rect
			(at 3.322574 -12.46505 270)
			(size 0.3556 1.2192)
			(layers "F.Cu" "F.Mask" "F.Paste")
			(net "RST_NIC2_PERST1_R_N")
		)
		(pad "A12" smd rect
			(at 3.322574 -11.865102 270)
			(size 0.3556 1.2192)
			(layers "F.Cu" "F.Mask" "F.Paste")
			(net "PRSNTB2_NIC2_N")
		)
		(pad "A13" smd rect
			(at 3.322574 -11.2649 270)
			(size 0.3556 1.2192)
			(layers "F.Cu" "F.Mask" "F.Paste")
			(net "GND")
		)
		(pad "A14" smd rect
			(at 3.322574 -10.664952 270)
			(size 0.3556 1.2192)
			(layers "F.Cu" "F.Mask" "F.Paste")
			(net "Net_2601")
		)
		(pad "A15" smd rect
			(at 3.322574 -10.065004 270)
			(size 0.3556 1.2192)
			(layers "F.Cu" "F.Mask" "F.Paste")
			(net "Net_2604")
		)
		(pad "A16" smd rect
			(at 3.322574 -9.465056 270)
			(size 0.3556 1.2192)
			(layers "F.Cu" "F.Mask" "F.Paste")
			(net "GND")
		)
		(pad "A17" smd rect
			(at 3.322574 -8.865108 270)
			(size 0.3556 1.2192)
			(layers "F.Cu" "F.Mask" "F.Paste")
			(net "P5E_PEX1_STN1_RX_DN<31>")
		)
		(pad "A18" smd rect
			(at 3.322574 -8.264906 270)
			(size 0.3556 1.2192)
			(layers "F.Cu" "F.Mask" "F.Paste")
			(net "P5E_PEX1_STN1_RX_DP<31>")
		)
		(pad "A19" smd rect
			(at 3.322574 -7.664958 270)
			(size 0.3556 1.2192)
			(layers "F.Cu" "F.Mask" "F.Paste")
			(net "GND")
		)
		(pad "A20" smd rect
			(at 3.322574 -7.06501 270)
			(size 0.3556 1.2192)
			(layers "F.Cu" "F.Mask" "F.Paste")
			(net "P5E_PEX1_STN1_RX_DN<30>")
		)
		(pad "A21" smd rect
			(at 3.322574 -6.465062 270)
			(size 0.3556 1.2192)
			(layers "F.Cu" "F.Mask" "F.Paste")
			(net "P5E_PEX1_STN1_RX_DP<30>")
		)
		(pad "A22" smd rect
			(at 3.322574 -5.865114 270)
			(size 0.3556 1.2192)
			(layers "F.Cu" "F.Mask" "F.Paste")
			(net "GND")
		)
		(pad "A23" smd rect
			(at 3.322574 -5.264912 270)
			(size 0.3556 1.2192)
			(layers "F.Cu" "F.Mask" "F.Paste")
			(net "P5E_PEX1_STN1_RX_DN<29>")
		)
		(pad "A24" smd rect
			(at 3.322574 -4.664964 270)
			(size 0.3556 1.2192)
			(layers "F.Cu" "F.Mask" "F.Paste")
			(net "P5E_PEX1_STN1_RX_DP<29>")
		)
		(pad "A25" smd rect
			(at 3.322574 -4.065016 270)
			(size 0.3556 1.2192)
			(layers "F.Cu" "F.Mask" "F.Paste")
			(net "GND")
		)
		(pad "A26" smd rect
			(at 3.322574 -3.465068 270)
			(size 0.3556 1.2192)
			(layers "F.Cu" "F.Mask" "F.Paste")
			(net "P5E_PEX1_STN1_RX_DN<28>")
		)
		(pad "A27" smd rect
			(at 3.322574 -2.86512 270)
			(size 0.3556 1.2192)
			(layers "F.Cu" "F.Mask" "F.Paste")
			(net "P5E_PEX1_STN1_RX_DP<28>")
		)
		(pad "A28" smd rect
			(at 3.322574 -2.264918 270)
			(size 0.3556 1.2192)
			(layers "F.Cu" "F.Mask" "F.Paste")
			(net "GND")
		)
		(pad "A29" smd rect
			(at 3.322574 1.74498 270)
			(size 0.3556 1.2192)
			(layers "F.Cu" "F.Mask" "F.Paste")
			(net "GND")
		)
		(pad "A30" smd rect
			(at 3.322574 2.344928 270)
			(size 0.3556 1.2192)
			(layers "F.Cu" "F.Mask" "F.Paste")
			(net "P5E_PEX1_STN1_RX_DN<27>")
		)
		(pad "A31" smd rect
			(at 3.322574 2.944876 270)
			(size 0.3556 1.2192)
			(layers "F.Cu" "F.Mask" "F.Paste")
			(net "P5E_PEX1_STN1_RX_DP<27>")
		)
		(pad "A32" smd rect
			(at 3.322574 3.545078 270)
			(size 0.3556 1.2192)
			(layers "F.Cu" "F.Mask" "F.Paste")
			(net "GND")
		)
		(pad "A33" smd rect
			(at 3.322574 4.145026 270)
			(size 0.3556 1.2192)
			(layers "F.Cu" "F.Mask" "F.Paste")
			(net "P5E_PEX1_STN1_RX_DN<26>")
		)
		(pad "A34" smd rect
			(at 3.322574 4.744974 270)
			(size 0.3556 1.2192)
			(layers "F.Cu" "F.Mask" "F.Paste")
			(net "P5E_PEX1_STN1_RX_DP<26>")
		)
		(pad "A35" smd rect
			(at 3.322574 5.344922 270)
			(size 0.3556 1.2192)
			(layers "F.Cu" "F.Mask" "F.Paste")
			(net "GND")
		)
		(pad "A36" smd rect
			(at 3.322574 5.945124 270)
			(size 0.3556 1.2192)
			(layers "F.Cu" "F.Mask" "F.Paste")
			(net "P5E_PEX1_STN1_RX_DN<25>")
		)
		(pad "A37" smd rect
			(at 3.322574 6.545072 270)
			(size 0.3556 1.2192)
			(layers "F.Cu" "F.Mask" "F.Paste")
			(net "P5E_PEX1_STN1_RX_DP<25>")
		)
		(pad "A38" smd rect
			(at 3.322574 7.14502 270)
			(size 0.3556 1.2192)
			(layers "F.Cu" "F.Mask" "F.Paste")
			(net "GND")
		)
		(pad "A39" smd rect
			(at 3.322574 7.744968 270)
			(size 0.3556 1.2192)
			(layers "F.Cu" "F.Mask" "F.Paste")
			(net "P5E_PEX1_STN1_RX_DN<24>")
		)
		(pad "A40" smd rect
			(at 3.322574 8.344916 270)
			(size 0.3556 1.2192)
			(layers "F.Cu" "F.Mask" "F.Paste")
			(net "P5E_PEX1_STN1_RX_DP<24>")
		)
		(pad "A41" smd rect
			(at 3.322574 8.945118 270)
			(size 0.3556 1.2192)
			(layers "F.Cu" "F.Mask" "F.Paste")
			(net "GND")
		)
		(pad "A42" smd rect
			(at 3.322574 9.545066 270)
			(size 0.3556 1.2192)
			(layers "F.Cu" "F.Mask" "F.Paste")
			(net "PRSNTB1_NIC2_N")
		)
		(pad "A43" smd rect
			(at 3.322574 14.454886 270)
			(size 0.3556 1.2192)
			(layers "F.Cu" "F.Mask" "F.Paste")
			(net "GND")
		)
		(pad "A44" smd rect
			(at 3.322574 15.055088 270)
			(size 0.3556 1.2192)
			(layers "F.Cu" "F.Mask" "F.Paste")
			(net "P5E_PEX1_STN1_RX_DN<23>")
		)
		(pad "A45" smd rect
			(at 3.322574 15.655036 270)
			(size 0.3556 1.2192)
			(layers "F.Cu" "F.Mask" "F.Paste")
			(net "P5E_PEX1_STN1_RX_DP<23>")
		)
		(pad "A46" smd rect
			(at 3.322574 16.254984 270)
			(size 0.3556 1.2192)
			(layers "F.Cu" "F.Mask" "F.Paste")
			(net "GND")
		)
		(pad "A47" smd rect
			(at 3.322574 16.854932 270)
			(size 0.3556 1.2192)
			(layers "F.Cu" "F.Mask" "F.Paste")
			(net "P5E_PEX1_STN1_RX_DN<22>")
		)
		(pad "A48" smd rect
			(at 3.322574 17.45488 270)
			(size 0.3556 1.2192)
			(layers "F.Cu" "F.Mask" "F.Paste")
			(net "P5E_PEX1_STN1_RX_DP<22>")
		)
		(pad "A49" smd rect
			(at 3.322574 18.055082 270)
			(size 0.3556 1.2192)
			(layers "F.Cu" "F.Mask" "F.Paste")
			(net "GND")
		)
		(pad "A50" smd rect
			(at 3.322574 18.65503 270)
			(size 0.3556 1.2192)
			(layers "F.Cu" "F.Mask" "F.Paste")
			(net "P5E_PEX1_STN1_RX_DN<21>")
		)
		(pad "A51" smd rect
			(at 3.322574 19.254978 270)
			(size 0.3556 1.2192)
			(layers "F.Cu" "F.Mask" "F.Paste")
			(net "P5E_PEX1_STN1_RX_DP<21>")
		)
		(pad "A52" smd rect
			(at 3.322574 19.854926 270)
			(size 0.3556 1.2192)
			(layers "F.Cu" "F.Mask" "F.Paste")
			(net "GND")
		)
		(pad "A53" smd rect
			(at 3.322574 20.455128 270)
			(size 0.3556 1.2192)
			(layers "F.Cu" "F.Mask" "F.Paste")
			(net "P5E_PEX1_STN1_RX_DN<20>")
		)
		(pad "A54" smd rect
			(at 3.322574 21.055076 270)
			(size 0.3556 1.2192)
			(layers "F.Cu" "F.Mask" "F.Paste")
			(net "P5E_PEX1_STN1_RX_DP<20>")
		)
		(pad "A55" smd rect
			(at 3.322574 21.655024 270)
			(size 0.3556 1.2192)
			(layers "F.Cu" "F.Mask" "F.Paste")
			(net "GND")
		)
		(pad "A56" smd rect
			(at 3.322574 22.254972 270)
			(size 0.3556 1.2192)
			(layers "F.Cu" "F.Mask" "F.Paste")
			(net "P5E_PEX1_STN1_RX_DN<19>")
		)
		(pad "A57" smd rect
			(at 3.322574 22.85492 270)
			(size 0.3556 1.2192)
			(layers "F.Cu" "F.Mask" "F.Paste")
			(net "P5E_PEX1_STN1_RX_DP<19>")
		)
		(pad "A58" smd rect
			(at 3.322574 23.455122 270)
			(size 0.3556 1.2192)
			(layers "F.Cu" "F.Mask" "F.Paste")
			(net "GND")
		)
		(pad "A59" smd rect
			(at 3.322574 24.05507 270)
			(size 0.3556 1.2192)
			(layers "F.Cu" "F.Mask" "F.Paste")
			(net "P5E_PEX1_STN1_RX_DN<18>")
		)
		(pad "A60" smd rect
			(at 3.322574 24.655018 270)
			(size 0.3556 1.2192)
			(layers "F.Cu" "F.Mask" "F.Paste")
			(net "P5E_PEX1_STN1_RX_DP<18>")
		)
		(pad "A61" smd rect
			(at 3.322574 25.254966 270)
			(size 0.3556 1.2192)
			(layers "F.Cu" "F.Mask" "F.Paste")
			(net "GND")
		)
		(pad "A62" smd rect
			(at 3.322574 25.854914 270)
			(size 0.3556 1.2192)
			(layers "F.Cu" "F.Mask" "F.Paste")
			(net "P5E_PEX1_STN1_RX_DN<17>")
		)
		(pad "A63" smd rect
			(at 3.322574 26.455116 270)
			(size 0.3556 1.2192)
			(layers "F.Cu" "F.Mask" "F.Paste")
			(net "P5E_PEX1_STN1_RX_DP<17>")
		)
		(pad "A64" smd rect
			(at 3.322574 27.055064 270)
			(size 0.3556 1.2192)
			(layers "F.Cu" "F.Mask" "F.Paste")
			(net "GND")
		)
		(pad "A65" smd rect
			(at 3.322574 27.655012 270)
			(size 0.3556 1.2192)
			(layers "F.Cu" "F.Mask" "F.Paste")
			(net "P5E_PEX1_STN1_RX_DN<16>")
		)
		(pad "A66" smd rect
			(at 3.322574 28.25496 270)
			(size 0.3556 1.2192)
			(layers "F.Cu" "F.Mask" "F.Paste")
			(net "P5E_PEX1_STN1_RX_DP<16>")
		)
		(pad "A67" smd rect
			(at 3.322574 28.854908 270)
			(size 0.3556 1.2192)
			(layers "F.Cu" "F.Mask" "F.Paste")
			(net "GND")
		)
		(pad "A68" smd rect
			(at 3.322574 29.45511 270)
			(size 0.3556 1.2192)
			(layers "F.Cu" "F.Mask" "F.Paste")
			(net "Net_2609")
		)
		(pad "A69" smd rect
			(at 3.322574 30.055058 270)
			(size 0.3556 1.2192)
			(layers "F.Cu" "F.Mask" "F.Paste")
			(net "Net_2610")
		)
		(pad "A70" smd rect
			(at 3.322574 30.655006 270)
			(size 0.3556 1.2192)
			(layers "F.Cu" "F.Mask" "F.Paste")
			(net "NIC2_PWRBRK_R_N")
		)
		(pad "B1" smd rect
			(at -1.27762 -18.465038 270)
			(size 0.3556 1.2192)
			(layers "F.Cu" "F.Mask" "F.Paste")
			(net "P12V_NIC2")
		)
		(pad "B2" smd rect
			(at -1.27762 -17.86509 270)
			(size 0.3556 1.2192)
			(layers "F.Cu" "F.Mask" "F.Paste")
			(net "P12V_NIC2")
		)
		(pad "B3" smd rect
			(at -1.27762 -17.264888 270)
			(size 0.3556 1.2192)
			(layers "F.Cu" "F.Mask" "F.Paste")
			(net "P12V_NIC2")
		)
		(pad "B4" smd rect
			(at -1.27762 -16.66494 270)
			(size 0.3556 1.2192)
			(layers "F.Cu" "F.Mask" "F.Paste")
			(net "P12V_NIC2")
		)
		(pad "B5" smd rect
			(at -1.27762 -16.064992 270)
			(size 0.3556 1.2192)
			(layers "F.Cu" "F.Mask" "F.Paste")
			(net "P12V_NIC2")
		)
		(pad "B6" smd rect
			(at -1.27762 -15.465044 270)
			(size 0.3556 1.2192)
			(layers "F.Cu" "F.Mask" "F.Paste")
			(net "P12V_NIC2")
		)
		(pad "B7" smd rect
			(at -1.27762 -14.865096 270)
			(size 0.3556 1.2192)
			(layers "F.Cu" "F.Mask" "F.Paste")
			(net "NIC2_BIF0_N")
		)
		(pad "B8" smd rect
			(at -1.27762 -14.264894 270)
			(size 0.3556 1.2192)
			(layers "F.Cu" "F.Mask" "F.Paste")
			(net "NIC2_BIF1_N")
		)
		(pad "B9" smd rect
			(at -1.27762 -13.664946 270)
			(size 0.3556 1.2192)
			(layers "F.Cu" "F.Mask" "F.Paste")
			(net "NIC2_BIF2_N")
		)
		(pad "B10" smd rect
			(at -1.27762 -13.064998 270)
			(size 0.3556 1.2192)
			(layers "F.Cu" "F.Mask" "F.Paste")
			(net "RST_NIC2_PERST0_R_N")
		)
		(pad "B11" smd rect
			(at -1.27762 -12.46505 270)
			(size 0.3556 1.2192)
			(layers "F.Cu" "F.Mask" "F.Paste")
			(net "P3V3_NIC2")
		)
		(pad "B12" smd rect
			(at -1.27762 -11.865102 270)
			(size 0.3556 1.2192)
			(layers "F.Cu" "F.Mask" "F.Paste")
			(net "NIC2_AUX_PWR_EN_R")
		)
		(pad "B13" smd rect
			(at -1.27762 -11.2649 270)
			(size 0.3556 1.2192)
			(layers "F.Cu" "F.Mask" "F.Paste")
			(net "GND")
		)
		(pad "B14" smd rect
			(at -1.27762 -10.664952 270)
			(size 0.3556 1.2192)
			(layers "F.Cu" "F.Mask" "F.Paste")
			(net "CLK_100M_DB2000QL_NIC2_R_DN")
		)
		(pad "B15" smd rect
			(at -1.27762 -10.065004 270)
			(size 0.3556 1.2192)
			(layers "F.Cu" "F.Mask" "F.Paste")
			(net "CLK_100M_DB2000QL_NIC2_R_DP")
		)
		(pad "B16" smd rect
			(at -1.27762 -9.465056 270)
			(size 0.3556 1.2192)
			(layers "F.Cu" "F.Mask" "F.Paste")
			(net "GND")
		)
		(pad "B17" smd rect
			(at -1.27762 -8.865108 270)
			(size 0.3556 1.2192)
			(layers "F.Cu" "F.Mask" "F.Paste")
			(net "P5E_PEX1_STN1_TX_C_DP<31>")
		)
		(pad "B18" smd rect
			(at -1.27762 -8.264906 270)
			(size 0.3556 1.2192)
			(layers "F.Cu" "F.Mask" "F.Paste")
			(net "P5E_PEX1_STN1_TX_C_DN<31>")
		)
		(pad "B19" smd rect
			(at -1.27762 -7.664958 270)
			(size 0.3556 1.2192)
			(layers "F.Cu" "F.Mask" "F.Paste")
			(net "GND")
		)
		(pad "B20" smd rect
			(at -1.27762 -7.06501 270)
			(size 0.3556 1.2192)
			(layers "F.Cu" "F.Mask" "F.Paste")
			(net "P5E_PEX1_STN1_TX_C_DN<30>")
		)
		(pad "B21" smd rect
			(at -1.27762 -6.465062 270)
			(size 0.3556 1.2192)
			(layers "F.Cu" "F.Mask" "F.Paste")
			(net "P5E_PEX1_STN1_TX_C_DP<30>")
		)
		(pad "B22" smd rect
			(at -1.27762 -5.865114 270)
			(size 0.3556 1.2192)
			(layers "F.Cu" "F.Mask" "F.Paste")
			(net "GND")
		)
		(pad "B23" smd rect
			(at -1.27762 -5.264912 270)
			(size 0.3556 1.2192)
			(layers "F.Cu" "F.Mask" "F.Paste")
			(net "P5E_PEX1_STN1_TX_C_DP<29>")
		)
		(pad "B24" smd rect
			(at -1.27762 -4.664964 270)
			(size 0.3556 1.2192)
			(layers "F.Cu" "F.Mask" "F.Paste")
			(net "P5E_PEX1_STN1_TX_C_DN<29>")
		)
		(pad "B25" smd rect
			(at -1.27762 -4.065016 270)
			(size 0.3556 1.2192)
			(layers "F.Cu" "F.Mask" "F.Paste")
			(net "GND")
		)
		(pad "B26" smd rect
			(at -1.27762 -3.465068 270)
			(size 0.3556 1.2192)
			(layers "F.Cu" "F.Mask" "F.Paste")
			(net "P5E_PEX1_STN1_TX_C_DN<28>")
		)
		(pad "B27" smd rect
			(at -1.27762 -2.86512 270)
			(size 0.3556 1.2192)
			(layers "F.Cu" "F.Mask" "F.Paste")
			(net "P5E_PEX1_STN1_TX_C_DP<28>")
		)
		(pad "B28" smd rect
			(at -1.27762 -2.264918 270)
			(size 0.3556 1.2192)
			(layers "F.Cu" "F.Mask" "F.Paste")
			(net "GND")
		)
		(pad "B29" smd rect
			(at -1.27762 1.74498 270)
			(size 0.3556 1.2192)
			(layers "F.Cu" "F.Mask" "F.Paste")
			(net "GND")
		)
		(pad "B30" smd rect
			(at -1.27762 2.344928 270)
			(size 0.3556 1.2192)
			(layers "F.Cu" "F.Mask" "F.Paste")
			(net "P5E_PEX1_STN1_TX_C_DP<27>")
		)
		(pad "B31" smd rect
			(at -1.27762 2.944876 270)
			(size 0.3556 1.2192)
			(layers "F.Cu" "F.Mask" "F.Paste")
			(net "P5E_PEX1_STN1_TX_C_DN<27>")
		)
		(pad "B32" smd rect
			(at -1.27762 3.545078 270)
			(size 0.3556 1.2192)
			(layers "F.Cu" "F.Mask" "F.Paste")
			(net "GND")
		)
		(pad "B33" smd rect
			(at -1.27762 4.145026 270)
			(size 0.3556 1.2192)
			(layers "F.Cu" "F.Mask" "F.Paste")
			(net "P5E_PEX1_STN1_TX_C_DN<26>")
		)
		(pad "B34" smd rect
			(at -1.27762 4.744974 270)
			(size 0.3556 1.2192)
			(layers "F.Cu" "F.Mask" "F.Paste")
			(net "P5E_PEX1_STN1_TX_C_DP<26>")
		)
		(pad "B35" smd rect
			(at -1.27762 5.344922 270)
			(size 0.3556 1.2192)
			(layers "F.Cu" "F.Mask" "F.Paste")
			(net "GND")
		)
		(pad "B36" smd rect
			(at -1.27762 5.945124 270)
			(size 0.3556 1.2192)
			(layers "F.Cu" "F.Mask" "F.Paste")
			(net "P5E_PEX1_STN1_TX_C_DP<25>")
		)
		(pad "B37" smd rect
			(at -1.27762 6.545072 270)
			(size 0.3556 1.2192)
			(layers "F.Cu" "F.Mask" "F.Paste")
			(net "P5E_PEX1_STN1_TX_C_DN<25>")
		)
	)
)
